(kicad_pcb
	(version 20260206)
	(generator "pcbnew")
	(generator_version "10.0")
	(general
		(thickness 1.6)
		(legacy_teardrops no)
	)
	(paper "A4")
	(title_block
		(title "01162023_DA0F0TEBIF0_F0T_Expander_BD_F_brd_V02_OCP.brd")
		(comment 1 "Grand Teton / footprints 192-198 of 9728")
	)
	(layers
		(0 "F.Cu" signal "TOP")
		(4 "In1.Cu" signal "GND")
		(6 "In2.Cu" signal "VCC")
		(8 "In3.Cu" signal "VCC1")
		(10 "In4.Cu" signal "GND1")
		(12 "In5.Cu" signal "IN1")
		(14 "In6.Cu" signal "GND2")
		(16 "In7.Cu" signal "IN2")
		(18 "In8.Cu" signal "GND3")
		(20 "In9.Cu" signal "IN3")
		(22 "In10.Cu" signal "GND4")
		(24 "In11.Cu" signal "IN4")
		(26 "In12.Cu" signal "GND5")
		(28 "In13.Cu" signal "IN5")
		(30 "In14.Cu" signal "GND6")
		(32 "In15.Cu" signal "IN6")
		(34 "In16.Cu" signal "GND7")
		(2 "B.Cu" signal "BOTTOM")
		(9 "F.Adhes" user "F.Adhesive")
		(11 "B.Adhes" user "B.Adhesive")
		(13 "F.Paste" user "Package Geometry/Pastemask Top")
		(15 "B.Paste" user "Package Geometry/Pastemask Bottom")
		(5 "F.SilkS" user "Ref Des/Silkscreen Top")
		(7 "B.SilkS" user "Ref Des/Silkscreen Bottom")
		(1 "F.Mask" user "Board Geometry/Soldermask Top")
		(3 "B.Mask" user "Board Geometry/Soldermask Bottom")
		(17 "Dwgs.User" user "User.Drawings")
		(19 "Cmts.User" user "User.Comments")
		(21 "Eco1.User" user "User.Eco1")
		(23 "Eco2.User" user "User.Eco2")
		(25 "Edge.Cuts" user "Board Geometry/Outline")
		(27 "Margin" user)
		(31 "F.CrtYd" user "Package Geometry/Place Bound Top")
		(29 "B.CrtYd" user "Package Geometry/Place Bound Bottom")
		(35 "F.Fab" user "Ref Des/Assembly Top")
		(33 "B.Fab" user "Ref Des/Assembly Bottom")
	)
	(footprint ""
		(layer "F.Cu")
		(at 289.634422 -356.244906 90)
		(property "Reference" "C591"
			(at 0 0 90)
			(layer "F.SilkS")
			(hide yes)
			(effects
				(font
					(size 1.27 1.27)
				)
			)
		)
		(property "Value" ""
			(at 0 0 90)
			(layer "F.Fab")
			(effects
				(font
					(size 1.27 1.27)
				)
			)
		)
		(duplicate_pad_numbers_are_jumpers no)
		(fp_line
			(start 0.299974 -0.150114)
			(end 0.299974 0.150114)
			(stroke
				(width 0.1)
				(type default)
			)
			(layer "F.Fab")
		)
		(fp_line
			(start -0.299974 -0.150114)
			(end 0.299974 -0.150114)
			(stroke
				(width 0.1)
				(type default)
			)
			(layer "F.Fab")
		)
		(fp_line
			(start 0.299974 0.150114)
			(end -0.299974 0.150114)
			(stroke
				(width 0.1)
				(type default)
			)
			(layer "F.Fab")
		)
		(fp_line
			(start -0.299974 0.150114)
			(end -0.299974 -0.150114)
			(stroke
				(width 0.1)
				(type default)
			)
			(layer "F.Fab")
		)
		(pad "1" smd rect
			(at -0.2667 0 90)
			(size 0.3048 0.381)
			(layers "F.Cu" "F.Mask" "F.Paste")
			(net "P5E_PEX2_STN7_TX_DP<123>")
		)
		(pad "2" smd rect
			(at 0.2667 0 90)
			(size 0.3048 0.381)
			(layers "F.Cu" "F.Mask" "F.Paste")
			(net "P5E_PEX2_STN7_TX_C_DP<123>")
		)
	)
	(footprint ""
		(layer "F.Cu")
		(at 241.444018 -236.682026 -90)
		(property "Reference" "R6237"
			(at 0 0 270)
			(layer "F.SilkS")
			(hide yes)
			(effects
				(font
					(size 1.27 1.27)
				)
			)
		)
		(property "Value" ""
			(at 0 0 270)
			(layer "F.Fab")
			(effects
				(font
					(size 1.27 1.27)
				)
			)
		)
		(duplicate_pad_numbers_are_jumpers no)
		(fp_line
			(start -0.7874 0.4064)
			(end -0.7874 -0.4064)
			(stroke
				(width 0.1524)
				(type default)
			)
			(layer "F.SilkS")
		)
		(fp_line
			(start 0.7874 0.4064)
			(end -0.7874 0.4064)
			(stroke
				(width 0.1524)
				(type default)
			)
			(layer "F.SilkS")
		)
		(fp_line
			(start -0.7874 -0.4064)
			(end 0.7874 -0.4064)
			(stroke
				(width 0.1524)
				(type default)
			)
			(layer "F.SilkS")
		)
		(fp_line
			(start 0.7874 -0.4064)
			(end 0.7874 0.4064)
			(stroke
				(width 0.1524)
				(type default)
			)
			(layer "F.SilkS")
		)
		(fp_line
			(start -0.67945 0.3048)
			(end -0.67945 -0.305054)
			(stroke
				(width 0.1)
				(type default)
			)
			(layer "F.Fab")
		)
		(fp_line
			(start -0.12065 0.3048)
			(end -0.67945 0.3048)
			(stroke
				(width 0.1)
				(type default)
			)
			(layer "F.Fab")
		)
		(fp_line
			(start 0.120396 0.3048)
			(end 0.120396 0.2794)
			(stroke
				(width 0.1)
				(type default)
			)
			(layer "F.Fab")
		)
		(fp_line
			(start 0.67945 0.3048)
			(end 0.120396 0.3048)
			(stroke
				(width 0.1)
				(type default)
			)
			(layer "F.Fab")
		)
		(fp_line
			(start -0.12065 0.2794)
			(end -0.12065 0.3048)
			(stroke
				(width 0.1)
				(type default)
			)
			(layer "F.Fab")
		)
		(fp_line
			(start 0.120396 0.2794)
			(end -0.12065 0.2794)
			(stroke
				(width 0.1)
				(type default)
			)
			(layer "F.Fab")
		)
		(fp_line
			(start -0.12065 -0.2794)
			(end 0.12065 -0.2794)
			(stroke
				(width 0.1)
				(type default)
			)
			(layer "F.Fab")
		)
		(fp_line
			(start 0.12065 -0.2794)
			(end 0.12065 -0.3048)
			(stroke
				(width 0.1)
				(type default)
			)
			(layer "F.Fab")
		)
		(fp_line
			(start 0.12065 -0.3048)
			(end 0.67945 -0.3048)
			(stroke
				(width 0.1)
				(type default)
			)
			(layer "F.Fab")
		)
		(fp_line
			(start 0.67945 -0.3048)
			(end 0.67945 0.3048)
			(stroke
				(width 0.1)
				(type default)
			)
			(layer "F.Fab")
		)
		(fp_line
			(start -0.67945 -0.305054)
			(end -0.12065 -0.305054)
			(stroke
				(width 0.1)
				(type default)
			)
			(layer "F.Fab")
		)
		(fp_line
			(start -0.12065 -0.305054)
			(end -0.12065 -0.2794)
			(stroke
				(width 0.1)
				(type default)
			)
			(layer "F.Fab")
		)
		(pad "1" smd circle
			(at -0.40005 0 270)
			(size 0 0)
			(layers "F.Cu" "F.Mask" "F.Paste")
			(net "BIC_RECOVER_IOEXP_A0")
		)
		(pad "2" smd circle
			(at 0.40005 0 270)
			(size 0 0)
			(layers "F.Cu" "F.Mask" "F.Paste")
			(net "GND")
		)
	)
	(footprint ""
		(layer "F.Cu")
		(at 118.054628 -350.098614 90)
		(property "Reference" "C362"
			(at 0 0 90)
			(layer "F.SilkS")
			(hide yes)
			(effects
				(font
					(size 1.27 1.27)
				)
			)
		)
		(property "Value" ""
			(at 0 0 90)
			(layer "F.Fab")
			(effects
				(font
					(size 1.27 1.27)
				)
			)
		)
		(duplicate_pad_numbers_are_jumpers no)
		(fp_line
			(start 0.299974 -0.150114)
			(end 0.299974 0.150114)
			(stroke
				(width 0.1)
				(type default)
			)
			(layer "F.Fab")
		)
		(fp_line
			(start -0.299974 -0.150114)
			(end 0.299974 -0.150114)
			(stroke
				(width 0.1)
				(type default)
			)
			(layer "F.Fab")
		)
		(fp_line
			(start 0.299974 0.150114)
			(end -0.299974 0.150114)
			(stroke
				(width 0.1)
				(type default)
			)
			(layer "F.Fab")
		)
		(fp_line
			(start -0.299974 0.150114)
			(end -0.299974 -0.150114)
			(stroke
				(width 0.1)
				(type default)
			)
			(layer "F.Fab")
		)
		(pad "1" smd rect
			(at -0.2667 0 90)
			(size 0.3048 0.381)
			(layers "F.Cu" "F.Mask" "F.Paste")
			(net "P5E_PEX1_STN6_TX_DP<100>")
		)
		(pad "2" smd rect
			(at 0.2667 0 90)
			(size 0.3048 0.381)
			(layers "F.Cu" "F.Mask" "F.Paste")
			(net "P5E_PEX1_STN6_TX_C_DP<100>")
		)
	)
	(footprint ""
		(layer "F.Cu")
		(at 242.310412 -123.947428 180)
		(property "Reference" "PR242"
			(at 0 0 180)
			(layer "F.SilkS")
			(hide yes)
			(effects
				(font
					(size 1.27 1.27)
				)
			)
		)
		(property "Value" ""
			(at 0 0 180)
			(layer "F.Fab")
			(effects
				(font
					(size 1.27 1.27)
				)
			)
		)
		(duplicate_pad_numbers_are_jumpers no)
		(fp_line
			(start 0.7874 0.4064)
			(end -0.7874 0.4064)
			(stroke
				(width 0.1524)
				(type default)
			)
			(layer "F.SilkS")
		)
		(fp_line
			(start 0.7874 -0.4064)
			(end 0.7874 0.4064)
			(stroke
				(width 0.1524)
				(type default)
			)
			(layer "F.SilkS")
		)
		(fp_line
			(start -0.7874 0.4064)
			(end -0.7874 -0.4064)
			(stroke
				(width 0.1524)
				(type default)
			)
			(layer "F.SilkS")
		)
		(fp_line
			(start -0.7874 -0.4064)
			(end 0.7874 -0.4064)
			(stroke
				(width 0.1524)
				(type default)
			)
			(layer "F.SilkS")
		)
		(fp_line
			(start 0.67945 0.3048)
			(end 0.120396 0.3048)
			(stroke
				(width 0.1)
				(type default)
			)
			(layer "F.Fab")
		)
		(fp_line
			(start 0.67945 -0.3048)
			(end 0.67945 0.3048)
			(stroke
				(width 0.1)
				(type default)
			)
			(layer "F.Fab")
		)
		(fp_line
			(start 0.12065 -0.2794)
			(end 0.12065 -0.3048)
			(stroke
				(width 0.1)
				(type default)
			)
			(layer "F.Fab")
		)
		(fp_line
			(start 0.12065 -0.3048)
			(end 0.67945 -0.3048)
			(stroke
				(width 0.1)
				(type default)
			)
			(layer "F.Fab")
		)
		(fp_line
			(start 0.120396 0.3048)
			(end 0.120396 0.2794)
			(stroke
				(width 0.1)
				(type default)
			)
			(layer "F.Fab")
		)
		(fp_line
			(start 0.120396 0.2794)
			(end -0.12065 0.2794)
			(stroke
				(width 0.1)
				(type default)
			)
			(layer "F.Fab")
		)
		(fp_line
			(start -0.12065 0.3048)
			(end -0.67945 0.3048)
			(stroke
				(width 0.1)
				(type default)
			)
			(layer "F.Fab")
		)
		(fp_line
			(start -0.12065 0.2794)
			(end -0.12065 0.3048)
			(stroke
				(width 0.1)
				(type default)
			)
			(layer "F.Fab")
		)
		(fp_line
			(start -0.12065 -0.2794)
			(end 0.12065 -0.2794)
			(stroke
				(width 0.1)
				(type default)
			)
			(layer "F.Fab")
		)
		(fp_line
			(start -0.12065 -0.305054)
			(end -0.12065 -0.2794)
			(stroke
				(width 0.1)
				(type default)
			)
			(layer "F.Fab")
		)
		(fp_line
			(start -0.67945 0.3048)
			(end -0.67945 -0.305054)
			(stroke
				(width 0.1)
				(type default)
			)
			(layer "F.Fab")
		)
		(fp_line
			(start -0.67945 -0.305054)
			(end -0.12065 -0.305054)
			(stroke
				(width 0.1)
				(type default)
			)
			(layer "F.Fab")
		)
		(pad "1" smd circle
			(at -0.40005 0 180)
			(size 0 0)
			(layers "F.Cu" "F.Mask" "F.Paste")
			(net "P3V3_NIC4_OCP")
		)
		(pad "2" smd circle
			(at 0.40005 0 180)
			(size 0 0)
			(layers "F.Cu" "F.Mask" "F.Paste")
			(net "GND")
		)
	)
	(footprint ""
		(layer "F.Cu")
		(at 361.188 -178.054 180)
		(property "Reference" "R4706"
			(at 0 0 180)
			(layer "F.SilkS")
			(hide yes)
			(effects
				(font
					(size 1.27 1.27)
				)
			)
		)
		(property "Value" ""
			(at 0 0 180)
			(layer "F.Fab")
			(effects
				(font
					(size 1.27 1.27)
				)
			)
		)
		(duplicate_pad_numbers_are_jumpers no)
		(fp_line
			(start 0.7874 0.4064)
			(end -0.7874 0.4064)
			(stroke
				(width 0.1524)
				(type default)
			)
			(layer "F.SilkS")
		)
		(fp_line
			(start 0.7874 -0.4064)
			(end 0.7874 0.4064)
			(stroke
				(width 0.1524)
				(type default)
			)
			(layer "F.SilkS")
		)
		(fp_line
			(start -0.7874 0.4064)
			(end -0.7874 -0.4064)
			(stroke
				(width 0.1524)
				(type default)
			)
			(layer "F.SilkS")
		)
		(fp_line
			(start -0.7874 -0.4064)
			(end 0.7874 -0.4064)
			(stroke
				(width 0.1524)
				(type default)
			)
			(layer "F.SilkS")
		)
		(fp_line
			(start 0.67945 0.3048)
			(end 0.120396 0.3048)
			(stroke
				(width 0.1)
				(type default)
			)
			(layer "F.Fab")
		)
		(fp_line
			(start 0.67945 -0.3048)
			(end 0.67945 0.3048)
			(stroke
				(width 0.1)
				(type default)
			)
			(layer "F.Fab")
		)
		(fp_line
			(start 0.12065 -0.2794)
			(end 0.12065 -0.3048)
			(stroke
				(width 0.1)
				(type default)
			)
			(layer "F.Fab")
		)
		(fp_line
			(start 0.12065 -0.3048)
			(end 0.67945 -0.3048)
			(stroke
				(width 0.1)
				(type default)
			)
			(layer "F.Fab")
		)
		(fp_line
			(start 0.120396 0.3048)
			(end 0.120396 0.2794)
			(stroke
				(width 0.1)
				(type default)
			)
			(layer "F.Fab")
		)
		(fp_line
			(start 0.120396 0.2794)
			(end -0.12065 0.2794)
			(stroke
				(width 0.1)
				(type default)
			)
			(layer "F.Fab")
		)
		(fp_line
			(start -0.12065 0.3048)
			(end -0.67945 0.3048)
			(stroke
				(width 0.1)
				(type default)
			)
			(layer "F.Fab")
		)
		(fp_line
			(start -0.12065 0.2794)
			(end -0.12065 0.3048)
			(stroke
				(width 0.1)
				(type default)
			)
			(layer "F.Fab")
		)
		(fp_line
			(start -0.12065 -0.2794)
			(end 0.12065 -0.2794)
			(stroke
				(width 0.1)
				(type default)
			)
			(layer "F.Fab")
		)
		(fp_line
			(start -0.12065 -0.305054)
			(end -0.12065 -0.2794)
			(stroke
				(width 0.1)
				(type default)
			)
			(layer "F.Fab")
		)
		(fp_line
			(start -0.67945 0.3048)
			(end -0.67945 -0.305054)
			(stroke
				(width 0.1)
				(type default)
			)
			(layer "F.Fab")
		)
		(fp_line
			(start -0.67945 -0.305054)
			(end -0.12065 -0.305054)
			(stroke
				(width 0.1)
				(type default)
			)
			(layer "F.Fab")
		)
		(pad "1" smd circle
			(at -0.40005 0 180)
			(size 0 0)
			(layers "F.Cu" "F.Mask" "F.Paste")
			(net "SSD6_PEX_PWR_EN")
		)
		(pad "2" smd circle
			(at 0.40005 0 180)
			(size 0 0)
			(layers "F.Cu" "F.Mask" "F.Paste")
			(net "SSD6_PEX_PWR_EN_R")
		)
	)
	(footprint ""
		(layer "F.Cu")
		(at 68.479162 -343.952322 90)
		(property "Reference" "C134"
			(at 0 0 90)
			(layer "F.SilkS")
			(hide yes)
			(effects
				(font
					(size 1.27 1.27)
				)
			)
		)
		(property "Value" ""
			(at 0 0 90)
			(layer "F.Fab")
			(effects
				(font
					(size 1.27 1.27)
				)
			)
		)
		(duplicate_pad_numbers_are_jumpers no)
		(fp_line
			(start 0.299974 -0.150114)
			(end 0.299974 0.150114)
			(stroke
				(width 0.1)
				(type default)
			)
			(layer "F.Fab")
		)
		(fp_line
			(start -0.299974 -0.150114)
			(end 0.299974 -0.150114)
			(stroke
				(width 0.1)
				(type default)
			)
			(layer "F.Fab")
		)
		(fp_line
			(start 0.299974 0.150114)
			(end -0.299974 0.150114)
			(stroke
				(width 0.1)
				(type default)
			)
			(layer "F.Fab")
		)
		(fp_line
			(start -0.299974 0.150114)
			(end -0.299974 -0.150114)
			(stroke
				(width 0.1)
				(type default)
			)
			(layer "F.Fab")
		)
		(pad "1" smd rect
			(at -0.2667 0 90)
			(size 0.3048 0.381)
			(layers "F.Cu" "F.Mask" "F.Paste")
			(net "P5E_PEX0_STN6_TX_DN<109>")
		)
		(pad "2" smd rect
			(at 0.2667 0 90)
			(size 0.3048 0.381)
			(layers "F.Cu" "F.Mask" "F.Paste")
			(net "P5E_PEX0_STN6_TX_C_DN<109>")
		)
	)
	(footprint ""
		(layer "F.Cu")
		(at 261.78129 -209.434684)
		(property "Reference" "JP2"
			(at 2.708656 18.429986 90)
			(unlocked yes)
			(layer "F.SilkS")
			(effects
				(font
					(size 0.7874 0.5842)
					(thickness 0.1524)
				)
				(justify left)
			)
		)
		(property "Value" ""
			(at 0 0 0)
			(layer "F.Fab")
			(effects
				(font
					(size 1.27 1.27)
				)
			)
		)
		(duplicate_pad_numbers_are_jumpers no)
		(fp_line
			(start -1.249934 -1.320038)
			(end 1.249934 -1.320038)
			(stroke
				(width 0.1524)
				(type default)
			)
			(layer "F.SilkS")
		)
		(fp_line
			(start -1.249934 19.100038)
			(end -1.249934 -1.320038)
			(stroke
				(width 0.1524)
				(type default)
			)
			(layer "F.SilkS")
		)
		(fp_line
			(start 1.249934 -1.320038)
			(end 1.249934 19.100038)
			(stroke
				(width 0.1524)
				(type default)
			)
			(layer "F.SilkS")
		)
		(fp_line
			(start 1.249934 19.100038)
			(end -1.249934 19.100038)
			(stroke
				(width 0.1524)
				(type default)
			)
			(layer "F.SilkS")
		)
		(fp_poly
			(pts
				(xy -0.626872 -2.74955) (xy 0.650748 -2.74955) (xy 0.011938 -1.472184)
			)
			(stroke
				(width 0)
				(type default)
			)
			(fill yes)
			(layer "F.SilkS")
		)
		(fp_line
			(start -1.249934 -1.320038)
			(end 1.249934 -1.320038)
			(stroke
				(width 0.1)
				(type default)
			)
			(layer "F.Fab")
		)
		(fp_line
			(start -1.249934 19.100038)
			(end -1.249934 -1.320038)
			(stroke
				(width 0.1)
				(type default)
			)
			(layer "F.Fab")
		)
		(fp_line
			(start 1.249934 -1.320038)
			(end 1.249934 19.100038)
			(stroke
				(width 0.1)
				(type default)
			)
			(layer "F.Fab")
		)
		(fp_line
			(start 1.249934 19.100038)
			(end -1.249934 19.100038)
			(stroke
				(width 0.1)
				(type default)
			)
			(layer "F.Fab")
		)
		(fp_poly
			(pts
				(xy -2.7432 0.63881) (xy -2.7432 -0.63881) (xy -1.465834 0)
			)
			(stroke
				(width 0)
				(type default)
			)
			(fill yes)
			(layer "F.Fab")
		)
		(fp_text user "8"
			(at -1.7526 17.80667 0)
			(unlocked yes)
			(layer "F.SilkS")
			(effects
				(font
					(size 0.7874 0.5842)
					(thickness 0.1524)
				)
			)
		)
		(fp_text user "8"
			(at -1.1938 17.80667 0)
			(unlocked yes)
			(layer "B.SilkS")
			(effects
				(font
					(size 0.7874 0.5842)
					(thickness 0.1524)
				)
				(justify mirror)
			)
		)
		(fp_text user "1"
			(at -1.1176 -0.02413 0)
			(unlocked yes)
			(layer "B.SilkS")
			(effects
				(font
					(size 0.7874 0.5842)
					(thickness 0.1524)
				)
				(justify mirror)
			)
		)
		(fp_text user "8"
			(at -1.1938 17.80667 0)
			(unlocked yes)
			(layer "B.Fab")
			(effects
				(font
					(size 0.7874 0.5842)
					(thickness 0.1524)
				)
				(justify mirror)
			)
		)
		(fp_text user "1"
			(at -1.1176 -0.02413 0)
			(unlocked yes)
			(layer "B.Fab")
			(effects
				(font
					(size 0.7874 0.5842)
					(thickness 0.1524)
				)
				(justify mirror)
			)
		)
		(fp_text user "8"
			(at -1.7526 17.80667 0)
			(unlocked yes)
			(layer "F.Fab")
			(effects
				(font
					(size 0.7874 0.5842)
					(thickness 0.1524)
				)
			)
		)
		(pad "1" thru_hole rect
			(at 0 0)
			(size 1.5494 1.5494)
			(drill 1.0414)
			(layers "*.Cu" "*.Mask")
			(remove_unused_layers no)
			(net "P3V3_AUX_JTAG")
			(clearance 0)
			(padstack
				(mode front_inner_back)
				(layer "Inner"
					(shape circle)
					(size 1.5494 1.5494)
					(clearance 0)
				)
				(layer "B.Cu"
					(shape rect)
					(size 1.5494 1.5494)
					(clearance 0)
				)
			)
		)
		(pad "2" thru_hole circle
			(at 0 2.54)
			(size 1.5494 1.5494)
			(drill 1.0414)
			(layers "*.Cu" "*.Mask")
			(remove_unused_layers no)
			(net "JTAG_CONN_TDO")
			(clearance 0)
		)
		(pad "3" thru_hole circle
			(at 0 5.08)
			(size 1.5494 1.5494)
			(drill 1.0414)
			(layers "*.Cu" "*.Mask")
			(remove_unused_layers no)
			(net "JTAG_CONN_TDI")
			(clearance 0)
		)
		(pad "4" thru_hole circle
			(at 0 7.62)
			(size 1.5494 1.5494)
			(drill 1.0414)
			(layers "*.Cu" "*.Mask")
			(remove_unused_layers no)
			(net "TP_JTAG_PIN4")
			(clearance 0)
		)
		(pad "5" thru_hole circle
			(at 0 10.16)
			(size 1.5494 1.5494)
			(drill 1.0414)
			(layers "*.Cu" "*.Mask")
			(remove_unused_layers no)
			(net "TP_JTAG_PIN5")
			(clearance 0)
		)
		(pad "6" thru_hole circle
			(at 0 12.7)
			(size 1.5494 1.5494)
			(drill 1.0414)
			(layers "*.Cu" "*.Mask")
			(remove_unused_layers no)
			(net "JTAG_CONN_TMS")
			(clearance 0)
		)
		(pad "7" thru_hole circle
			(at 0 15.24)
			(size 1.5494 1.5494)
			(drill 1.0414)
			(layers "*.Cu" "*.Mask")
			(remove_unused_layers no)
			(net "GND")
			(clearance 0)
		)
		(pad "8" thru_hole circle
			(at 0 17.78)
			(size 1.5494 1.5494)
			(drill 1.0414)
			(layers "*.Cu" "*.Mask")
			(remove_unused_layers no)
			(net "JTAG_CONN_TCK")
			(clearance 0)
		)
	)
)
